(kicad_pcb
	(version 20241229)
	(generator "pcbnew")
	(generator_version "9.0")
	(general
		(thickness 1.63)
		(legacy_teardrops no)
	)
	(paper "A4")
	(title_block
		(title "CM4 Baseboard")
		(date "2026-01-05")
		(rev "1.1.1")
		(company "Antmicro Ltd")
		(comment 1 "www.antmicro.com")
		(comment 9 "footprints 201-205 of 506")
	)
	(layers
		(0 "F.Cu" signal)
		(4 "In1.Cu" power)
		(6 "In2.Cu" power)
		(8 "In3.Cu" signal)
		(10 "In4.Cu" signal)
		(2 "B.Cu" signal)
		(9 "F.Adhes" user "F.Adhesive")
		(11 "B.Adhes" user "B.Adhesive")
		(13 "F.Paste" user)
		(15 "B.Paste" user)
		(5 "F.SilkS" user "F.Silkscreen")
		(7 "B.SilkS" user "B.Silkscreen")
		(1 "F.Mask" user)
		(3 "B.Mask" user)
		(17 "Dwgs.User" user "User.Drawings")
		(19 "Cmts.User" user "User.Comments")
		(21 "Eco1.User" user "User.Eco1")
		(23 "Eco2.User" user "User.Eco2")
		(25 "Edge.Cuts" user)
		(27 "Margin" user)
		(31 "F.CrtYd" user "F.Courtyard")
		(29 "B.CrtYd" user "B.Courtyard")
		(35 "F.Fab" user)
		(33 "B.Fab" user)
	)
	(footprint "antmicro-footprints:R_0402_1005Metric"
		(layer "F.Cu")
		(at 75.067962 167.6665 180)
		(descr "Resistor SMD 0402")
		(tags "resistor SMD 0402")
		(property "Reference" "R804"
			(at -1.4 1.35 0)
			(layer "F.SilkS")
			(effects
				(font
					(size 0.7 0.7)
					(thickness 0.15)
				)
				(justify right bottom)
			)
		)
		(property "Value" "R_10k_0402"
			(at -1.011843 1.772047 0)
			(layer "F.Fab")
			(effects
				(font
					(size 0.7 0.7)
					(thickness 0.15)
				)
				(justify right bottom)
			)
		)
		(property "Datasheet" "https://www.bourns.com/docs/product-datasheets/cr.pdf"
			(at 0 0 180)
			(layer "F.Fab")
			(hide yes)
			(effects
				(font
					(size 1.27 1.27)
					(thickness 0.15)
				)
			)
		)
		(property "MPN" "CR0402-FX-1002GLF"
			(at 0 0 180)
			(unlocked yes)
			(layer "F.Fab")
			(hide yes)
			(effects
				(font
					(size 1 1)
					(thickness 0.15)
				)
			)
		)
		(property "Manufacturer" "Bourns"
			(at 0 0 180)
			(unlocked yes)
			(layer "F.Fab")
			(hide yes)
			(effects
				(font
					(size 1 1)
					(thickness 0.15)
				)
			)
		)
		(property "License" "Apache-2.0"
			(at 0 0 180)
			(unlocked yes)
			(layer "F.Fab")
			(hide yes)
			(effects
				(font
					(size 1 1)
					(thickness 0.15)
				)
			)
		)
		(property "Author" "Antmicro"
			(at 0 0 180)
			(unlocked yes)
			(layer "F.Fab")
			(hide yes)
			(effects
				(font
					(size 1 1)
					(thickness 0.15)
				)
			)
		)
		(property "Val" "10k"
			(at 0 0 180)
			(unlocked yes)
			(layer "F.Fab")
			(hide yes)
			(effects
				(font
					(size 1 1)
					(thickness 0.15)
				)
			)
		)
		(property "Tolerance" "1%"
			(at 0 0 180)
			(unlocked yes)
			(layer "F.Fab")
			(hide yes)
			(effects
				(font
					(size 1 1)
					(thickness 0.15)
				)
			)
		)
		(sheetname "/Peripherals/")
		(sheetfile "peripherals.kicad_sch")
		(attr smd)
		(fp_rect
			(start -0.925 -0.47)
			(end 0.925 0.47)
			(stroke
				(width 0.05)
				(type default)
			)
			(fill no)
			(layer "F.CrtYd")
		)
		(fp_rect
			(start -0.5 -0.25)
			(end 0.5 0.25)
			(stroke
				(width 0.15)
				(type solid)
			)
			(fill no)
			(layer "F.Fab")
		)
		(fp_text user "${REFERENCE}"
			(at -0.95 3.168 180)
			(layer "F.Fab")
			(effects
				(font
					(size 0.7 0.7)
					(thickness 0.15)
				)
				(justify left bottom)
			)
		)
		(fp_text user "License: Apache-2.0"
			(at -0.95 5.169 180)
			(layer "F.Fab")
			(effects
				(font
					(size 0.7 0.7)
					(thickness 0.15)
				)
				(justify left bottom)
			)
		)
		(fp_text user "Author: Antmicro"
			(at -0.95 4.169 180)
			(layer "F.Fab")
			(effects
				(font
					(size 0.7 0.7)
					(thickness 0.15)
				)
				(justify left bottom)
			)
		)
		(pad "1" smd roundrect
			(at -0.48 0 180)
			(size 0.59 0.64)
			(layers "F.Cu" "F.Mask" "F.Paste")
			(roundrect_rratio 0.25)
			(net 3 "GND")
			(pintype "passive")
		)
		(pad "2" smd roundrect
			(at 0.48 0 180)
			(size 0.59 0.64)
			(layers "F.Cu" "F.Mask" "F.Paste")
			(roundrect_rratio 0.25)
			(net 374 "Net-(U801-I2C_ADR0)")
			(pintype "passive")
		)
	)
	(footprint "antmicro-footprints:Texas_X2QFN-12_1.6x1.6mm_P0.4mm"
		(layer "F.Cu")
		(at 99.567962 121.449 180)
		(descr "Texas  X2QFN, 12 Pin (http://www.ti.com/lit/ml/mpqf391c/mpqf391c.pdf), generated with kicad-footprint-generator ipc_noLead_generator.py")
		(tags "Texas X2QFN NoLead")
		(property "Reference" "U906"
			(at -28.64 -24.0475 90)
			(layer "F.SilkS")
			(effects
				(font
					(size 0.7 0.7)
					(thickness 0.15)
				)
				(justify right bottom)
			)
		)
		(property "Value" "TUSB321RWBR"
			(at -1.41 2.85 0)
			(layer "F.Fab")
			(effects
				(font
					(size 0.7 0.7)
					(thickness 0.15)
				)
				(justify right bottom)
			)
		)
		(property "Datasheet" "https://www.ti.com/lit/ds/symlink/tusb321.pdf?ts=1709901243739"
			(at 0 0 180)
			(layer "F.Fab")
			(hide yes)
			(effects
				(font
					(size 1.27 1.27)
					(thickness 0.15)
				)
			)
		)
		(property "MPN" "TUSB321RWBR"
			(at 0 0 180)
			(unlocked yes)
			(layer "F.Fab")
			(hide yes)
			(effects
				(font
					(size 1 1)
					(thickness 0.15)
				)
			)
		)
		(property "Manufacturer" "Texas Instruments"
			(at 0 0 180)
			(unlocked yes)
			(layer "F.Fab")
			(hide yes)
			(effects
				(font
					(size 1 1)
					(thickness 0.15)
				)
			)
		)
		(property "Author" "Antmicro"
			(at 0 0 180)
			(unlocked yes)
			(layer "F.Fab")
			(hide yes)
			(effects
				(font
					(size 1 1)
					(thickness 0.15)
				)
			)
		)
		(property "License" "Apache-2.0"
			(at 0 0 180)
			(unlocked yes)
			(layer "F.Fab")
			(hide yes)
			(effects
				(font
					(size 1 1)
					(thickness 0.15)
				)
			)
		)
		(sheetname "/USB/")
		(sheetfile "usb.kicad_sch")
		(attr smd)
		(fp_line
			(start 0.91 0.91)
			(end 0.91 0.56)
			(stroke
				(width 0.15)
				(type solid)
			)
			(layer "F.SilkS")
		)
		(fp_line
			(start 0.91 -0.912)
			(end 0.91 -0.562)
			(stroke
				(width 0.15)
				(type solid)
			)
			(layer "F.SilkS")
		)
		(fp_line
			(start -0.912 0.91)
			(end -0.912 0.56)
			(stroke
				(width 0.15)
				(type solid)
			)
			(layer "F.SilkS")
		)
		(fp_circle
			(center -1.3 -0.2)
			(end -1.25 -0.2)
			(stroke
				(width 0.15)
				(type solid)
			)
			(fill yes)
			(layer "F.SilkS")
		)
		(fp_line
			(start 1.39 1.39)
			(end 1.39 -1.41)
			(stroke
				(width 0.05)
				(type solid)
			)
			(layer "F.CrtYd")
		)
		(fp_line
			(start 1.39 -1.41)
			(end -1.41 -1.41)
			(stroke
				(width 0.05)
				(type solid)
			)
			(layer "F.CrtYd")
		)
		(fp_line
			(start -1.41 1.39)
			(end 1.39 1.39)
			(stroke
				(width 0.05)
				(type solid)
			)
			(layer "F.CrtYd")
		)
		(fp_line
			(start -1.41 -1.41)
			(end -1.41 1.39)
			(stroke
				(width 0.05)
				(type solid)
			)
			(layer "F.CrtYd")
		)
		(fp_line
			(start 0.8 0.8)
			(end -0.802 0.8)
			(stroke
				(width 0.15)
				(type solid)
			)
			(layer "F.Fab")
		)
		(fp_line
			(start 0.8 -0.802)
			(end 0.8 0.8)
			(stroke
				(width 0.15)
				(type solid)
			)
			(layer "F.Fab")
		)
		(fp_line
			(start -0.402 -0.802)
			(end 0.8 -0.802)
			(stroke
				(width 0.15)
				(type solid)
			)
			(layer "F.Fab")
		)
		(fp_line
			(start -0.802 0.8)
			(end -0.802 -0.402)
			(stroke
				(width 0.15)
				(type solid)
			)
			(layer "F.Fab")
		)
		(fp_line
			(start -0.802 -0.402)
			(end -0.402 -0.802)
			(stroke
				(width 0.15)
				(type solid)
			)
			(layer "F.Fab")
		)
		(fp_text user "Author: Antmicro"
			(at -1.76 7.25 180)
			(layer "F.Fab")
			(effects
				(font
					(size 0.7 0.7)
					(thickness 0.15)
				)
				(justify left bottom)
			)
		)
		(fp_text user "License: Apache-2.0"
			(at -1.76 4.85 180)
			(layer "F.Fab")
			(effects
				(font
					(size 0.7 0.7)
					(thickness 0.15)
				)
				(justify left bottom)
			)
		)
		(fp_text user "${REFERENCE}"
			(at -1.76 6.05 180)
			(layer "F.Fab")
			(effects
				(font
					(size 0.7 0.7)
					(thickness 0.15)
				)
				(justify left bottom)
			)
		)
		(pad "1" smd roundrect
			(at -0.725 -0.2 180)
			(size 0.85 0.2)
			(layers "F.Cu" "F.Mask" "F.Paste")
			(roundrect_rratio 0.25)
			(net 203 "/USB/USBA_CC1")
			(pinfunction "CC1")
			(pintype "bidirectional")
		)
		(pad "2" smd roundrect
			(at -0.725 0.2 180)
			(size 0.85 0.2)
			(layers "F.Cu" "F.Mask" "F.Paste")
			(roundrect_rratio 0.25)
			(net 204 "/USB/USBA_CC2")
			(pinfunction "CC2")
			(pintype "bidirectional")
		)
		(pad "3" smd roundrect
			(at -0.6 0.825 180)
			(size 0.2 0.65)
			(layers "F.Cu" "F.Mask" "F.Paste")
			(roundrect_rratio 0.25)
			(net 432 "Net-(U906-CURRENT_MODE)")
			(pinfunction "CURRENT_MODE")
			(pintype "input")
		)
		(pad "4" smd roundrect
			(at -0.2 0.825 180)
			(size 0.2 0.65)
			(layers "F.Cu" "F.Mask" "F.Paste")
			(roundrect_rratio 0.25)
			(net 434 "Net-(U906-PORT)")
			(pinfunction "PORT")
			(pintype "input")
		)
		(pad "5" smd roundrect
			(at 0.2 0.825 180)
			(size 0.2 0.65)
			(layers "F.Cu" "F.Mask" "F.Paste")
			(roundrect_rratio 0.25)
			(net 340 "Net-(U906-VBUS_DET)")
			(pinfunction "VBUS_DET")
			(pintype "input")
		)
		(pad "6" smd roundrect
			(at 0.6 0.825 180)
			(size 0.2 0.65)
			(layers "F.Cu" "F.Mask" "F.Paste")
			(roundrect_rratio 0.25)
			(net 435 "Net-(U906-~{VCONN_FAULT})")
			(pinfunction "~{VCONN_FAULT}")
			(pintype "open_collector")
		)
		(pad "7" smd roundrect
			(at 0.725 0.2 180)
			(size 0.85 0.2)
			(layers "F.Cu" "F.Mask" "F.Paste")
			(roundrect_rratio 0.25)
			(net 436 "Net-(U906-OUT1)")
			(pinfunction "OUT1")
			(pintype "open_collector")
		)
		(pad "8" smd roundrect
			(at 0.725 -0.2 180)
			(size 0.85 0.2)
			(layers "F.Cu" "F.Mask" "F.Paste")
			(roundrect_rratio 0.25)
			(net 437 "Net-(U906-OUT2)")
			(pinfunction "OUT2")
			(pintype "open_collector")
		)
		(pad "9" smd roundrect
			(at 0.6 -0.825 180)
			(size 0.2 0.65)
			(layers "F.Cu" "F.Mask" "F.Paste")
			(roundrect_rratio 0.25)
			(net 279 "/Compute module/USB.OTGID")
			(pinfunction "ID")
			(pintype "open_collector")
		)
		(pad "10" smd roundrect
			(at 0.2 -0.825 180)
			(size 0.2 0.65)
			(layers "F.Cu" "F.Mask" "F.Paste")
			(roundrect_rratio 0.25)
			(net 3 "GND")
			(pinfunction "GND")
			(pintype "power_in")
		)
		(pad "11" smd roundrect
			(at -0.2 -0.825 180)
			(size 0.2 0.65)
			(layers "F.Cu" "F.Mask" "F.Paste")
			(roundrect_rratio 0.25)
			(net 433 "Net-(U906-DIR)")
			(pinfunction "DIR")
			(pintype "open_collector")
		)
		(pad "12" smd roundrect
			(at -0.6 -0.825 180)
			(size 0.2 0.65)
			(layers "F.Cu" "F.Mask" "F.Paste")
			(roundrect_rratio 0.25)
			(net 28 "/USB/+5V_{CAP}")
			(pinfunction "VDD")
			(pintype "power_in")
		)
	)
	(footprint "antmicro-footprints:R_0402_1005Metric"
		(layer "F.Cu")
		(at 135.137962 157.6465 90)
		(descr "Resistor SMD 0402")
		(tags "resistor SMD 0402")
		(property "Reference" "R602"
			(at -7.23 1.65 90)
			(layer "F.SilkS")
			(effects
				(font
					(size 0.7 0.7)
					(thickness 0.15)
				)
				(justify left bottom)
			)
		)
		(property "Value" "R_10k_0402"
			(at -1.011843 1.772047 90)
			(layer "F.Fab")
			(effects
				(font
					(size 0.7 0.7)
					(thickness 0.15)
				)
				(justify left bottom)
			)
		)
		(property "Datasheet" "https://www.bourns.com/docs/product-datasheets/cr.pdf"
			(at 0 0 90)
			(layer "F.Fab")
			(hide yes)
			(effects
				(font
					(size 1.27 1.27)
					(thickness 0.15)
				)
			)
		)
		(property "Manufacturer" "Bourns"
			(at 0 0 90)
			(unlocked yes)
			(layer "F.Fab")
			(hide yes)
			(effects
				(font
					(size 1 1)
					(thickness 0.15)
				)
			)
		)
		(property "MPN" "CR0402-FX-1002GLF"
			(at 0 0 90)
			(unlocked yes)
			(layer "F.Fab")
			(hide yes)
			(effects
				(font
					(size 1 1)
					(thickness 0.15)
				)
			)
		)
		(property "Val" "10k"
			(at 0 0 90)
			(unlocked yes)
			(layer "F.Fab")
			(hide yes)
			(effects
				(font
					(size 1 1)
					(thickness 0.15)
				)
			)
		)
		(property "License" "Apache-2.0"
			(at 0 0 90)
			(unlocked yes)
			(layer "F.Fab")
			(hide yes)
			(effects
				(font
					(size 1 1)
					(thickness 0.15)
				)
			)
		)
		(property "Author" "Antmicro"
			(at 0 0 90)
			(unlocked yes)
			(layer "F.Fab")
			(hide yes)
			(effects
				(font
					(size 1 1)
					(thickness 0.15)
				)
			)
		)
		(property "Tolerance" "1%"
			(at 0 0 90)
			(unlocked yes)
			(layer "F.Fab")
			(hide yes)
			(effects
				(font
					(size 1 1)
					(thickness 0.15)
				)
			)
		)
		(sheetname "/CSI/")
		(sheetfile "csi.kicad_sch")
		(attr smd)
		(fp_rect
			(start -0.925 -0.47)
			(end 0.925 0.47)
			(stroke
				(width 0.05)
				(type default)
			)
			(fill no)
			(layer "F.CrtYd")
		)
		(fp_rect
			(start -0.5 -0.25)
			(end 0.5 0.25)
			(stroke
				(width 0.15)
				(type solid)
			)
			(fill no)
			(layer "F.Fab")
		)
		(fp_text user "${REFERENCE}"
			(at -0.95 3.168 90)
			(layer "F.Fab")
			(effects
				(font
					(size 0.7 0.7)
					(thickness 0.15)
				)
				(justify left bottom)
			)
		)
		(fp_text user "License: Apache-2.0"
			(at -0.95 5.169 90)
			(layer "F.Fab")
			(effects
				(font
					(size 0.7 0.7)
					(thickness 0.15)
				)
				(justify left bottom)
			)
		)
		(fp_text user "Author: Antmicro"
			(at -0.95 4.169 90)
			(layer "F.Fab")
			(effects
				(font
					(size 0.7 0.7)
					(thickness 0.15)
				)
				(justify left bottom)
			)
		)
		(pad "1" smd roundrect
			(at -0.48 0 90)
			(size 0.59 0.64)
			(layers "F.Cu" "F.Mask" "F.Paste")
			(roundrect_rratio 0.25)
			(net 10 "+5V")
			(pintype "passive")
		)
		(pad "2" smd roundrect
			(at 0.48 0 90)
			(size 0.59 0.64)
			(layers "F.Cu" "F.Mask" "F.Paste")
			(roundrect_rratio 0.25)
			(net 370 "Net-(U601-FLG)")
			(pintype "passive")
		)
	)
	(footprint "antmicro-footprints:TP_SMD_0.75mm"
		(layer "F.Cu")
		(at 81.4 120.4165)
		(property "Reference" "TP920"
			(at -3.61 0.1735 0)
			(layer "F.SilkS")
			(effects
				(font
					(size 0.7 0.7)
					(thickness 0.15)
				)
				(justify left bottom)
			)
		)
		(property "Value" "TP_0.75mm_SMD"
			(at 0 1.2 0)
			(layer "F.Fab")
			(effects
				(font
					(size 0.7 0.7)
					(thickness 0.15)
				)
				(justify left bottom)
			)
		)
		(property "MPN" ""
			(at 0 0 0)
			(unlocked yes)
			(layer "F.Fab")
			(hide yes)
			(effects
				(font
					(size 1 1)
					(thickness 0.15)
				)
			)
		)
		(property "Manufacturer" ""
			(at 0 0 0)
			(unlocked yes)
			(layer "F.Fab")
			(hide yes)
			(effects
				(font
					(size 1 1)
					(thickness 0.15)
				)
			)
		)
		(property "Author" "Antmicro"
			(at 0 0 0)
			(unlocked yes)
			(layer "F.Fab")
			(hide yes)
			(effects
				(font
					(size 1 1)
					(thickness 0.15)
				)
			)
		)
		(property "License" "Apache-2.0"
			(at 0 0 0)
			(unlocked yes)
			(layer "F.Fab")
			(hide yes)
			(effects
				(font
					(size 1 1)
					(thickness 0.15)
				)
			)
		)
		(sheetname "/USB/")
		(sheetfile "usb.kicad_sch")
		(attr exclude_from_pos_files exclude_from_bom)
		(fp_circle
			(center 0 0)
			(end 0.475 0)
			(stroke
				(width 0.05)
				(type default)
			)
			(fill no)
			(layer "F.CrtYd")
		)
		(fp_text user "Author: Antmicro"
			(at -0.4 3.901 0)
			(layer "F.Fab")
			(effects
				(font
					(size 0.7 0.7)
					(thickness 0.15)
				)
				(justify left bottom)
			)
		)
		(fp_text user "${REFERENCE}"
			(at -0.4 2.7 0)
			(layer "F.Fab")
			(effects
				(font
					(size 0.7 0.7)
					(thickness 0.15)
				)
				(justify left bottom)
			)
		)
		(fp_text user "License: Apache-2.0"
			(at -0.4 5.101 0)
			(layer "F.Fab")
			(effects
				(font
					(size 0.7 0.7)
					(thickness 0.15)
				)
				(justify left bottom)
			)
		)
		(pad "1" smd circle
			(at 0 0)
			(size 0.75 0.75)
			(layers "F.Cu" "F.Mask")
			(net 26 "/USB/USBD_VBUS")
			(pinfunction "1")
			(pintype "passive")
		)
	)
	(footprint "antmicro-footprints:C_0402_1005Metric"
		(layer "F.Cu")
		(at 83.567962 140.307236)
		(descr "Capacitor SMD 0402")
		(tags "capacitor SMD 0402")
		(property "Reference" "C924"
			(at -3.86 0.499264 0)
			(layer "F.SilkS")
			(effects
				(font
					(size 0.7 0.7)
					(thickness 0.15)
				)
				(justify left bottom)
			)
		)
		(property "Value" "C_4u7_0402"
			(at -1.022927 2.155213 0)
			(layer "F.Fab")
			(effects
				(font
					(size 0.7 0.7)
					(thickness 0.15)
				)
				(justify left bottom)
			)
		)
		(property "Datasheet" "https://www.murata.com/products/productdetail?partno=GRM155R61A475MEAA%23"
			(at 0 0 0)
			(layer "F.Fab")
			(hide yes)
			(effects
				(font
					(size 1.27 1.27)
					(thickness 0.15)
				)
			)
		)
		(property "Manufacturer" "Murata"
			(at 0 0 0)
			(unlocked yes)
			(layer "F.Fab")
			(hide yes)
			(effects
				(font
					(size 1 1)
					(thickness 0.15)
				)
			)
		)
		(property "MPN" "GRM155R61A475MEAAD"
			(at 0 0 0)
			(unlocked yes)
			(layer "F.Fab")
			(hide yes)
			(effects
				(font
					(size 1 1)
					(thickness 0.15)
				)
			)
		)
		(property "Val" "4u7"
			(at 0 0 0)
			(unlocked yes)
			(layer "F.Fab")
			(hide yes)
			(effects
				(font
					(size 1 1)
					(thickness 0.15)
				)
			)
		)
		(property "License" "Apache-2.0"
			(at 0 0 0)
			(unlocked yes)
			(layer "F.Fab")
			(hide yes)
			(effects
				(font
					(size 1 1)
					(thickness 0.15)
				)
			)
		)
		(property "Author" "Antmicro"
			(at 0 0 0)
			(unlocked yes)
			(layer "F.Fab")
			(hide yes)
			(effects
				(font
					(size 1 1)
					(thickness 0.15)
				)
			)
		)
		(property "Voltage" ""
			(at 0 0 0)
			(unlocked yes)
			(layer "F.Fab")
			(hide yes)
			(effects
				(font
					(size 1 1)
					(thickness 0.15)
				)
			)
		)
		(property "Dielectric" ""
			(at 0 0 0)
			(unlocked yes)
			(layer "F.Fab")
			(hide yes)
			(effects
				(font
					(size 1 1)
					(thickness 0.15)
				)
			)
		)
		(sheetname "/USB/")
		(sheetfile "usb.kicad_sch")
		(attr smd)
		(fp_rect
			(start -0.925 -0.47)
			(end 0.925 0.47)
			(stroke
				(width 0.05)
				(type default)
			)
			(fill no)
			(layer "F.CrtYd")
		)
		(fp_line
			(start -0.494 -0.25)
			(end 0.504 -0.25)
			(stroke
				(width 0.15)
				(type solid)
			)
			(layer "F.Fab")
		)
		(fp_line
			(start -0.494 0.248)
			(end -0.494 -0.25)
			(stroke
				(width 0.15)
				(type solid)
			)
			(layer "F.Fab")
		)
		(fp_line
			(start 0.504 -0.25)
			(end 0.504 0.248)
			(stroke
				(width 0.15)
				(type solid)
			)
			(layer "F.Fab")
		)
		(fp_line
			(start 0.504 0.248)
			(end -0.494 0.248)
			(stroke
				(width 0.15)
				(type solid)
			)
			(layer "F.Fab")
		)
		(fp_text user "${REFERENCE}"
			(at -0.939 4.599 0)
			(layer "F.Fab")
			(effects
				(font
					(size 0.7 0.7)
					(thickness 0.15)
				)
				(justify left bottom)
			)
		)
		(fp_text user "License: Apache-2.0"
			(at -0.939 5.799 0)
			(layer "F.Fab")
			(effects
				(font
					(size 0.7 0.7)
					(thickness 0.15)
				)
				(justify left bottom)
			)
		)
		(fp_text user "Author: Antmicro"
			(at -0.939 3.399 0)
			(layer "F.Fab")
			(effects
				(font
					(size 0.7 0.7)
					(thickness 0.15)
				)
				(justify left bottom)
			)
		)
		(pad "1" smd roundrect
			(at -0.48 0)
			(size 0.59 0.64)
			(layers "F.Cu" "F.Mask" "F.Paste")
			(roundrect_rratio 0.25)
			(net 3 "GND")
			(pintype "passive")
		)
		(pad "2" smd roundrect
			(at 0.48 0)
			(size 0.59 0.64)
			(layers "F.Cu" "F.Mask" "F.Paste")
			(roundrect_rratio 0.25)
			(net 27 "/USB/USB_3V3")
			(pintype "passive")
		)
	)
)
